# T6G (Grand Teton) — schematic netlist excerpt (pin names and nets, part order shuffled) for the footprints in the layout excerpt that follows; sources: Cadence DE-HDL packaged netlist, KiCad conversion of 04192023_DAF0TMB3IC0_F0TG_MB_C_brd_V02_OCP.brd

R6008  Q_RES  0 5% CHIP  pkg 0402LF  page 150 : A = SGPIO_SCM_DO_<0> ; B = SGPIO_SCM_DO_R_<0>
PR133  Q_RES  4.87K 1% EMPTY  pkg 0402LF  page 208 : A = GND ; B = PVDD11_S3_P0_LSET1

(kicad_pcb
	(version 20260206)
	(generator "pcbnew")
	(generator_version "10.0")
	(general
		(thickness 1.6)
		(legacy_teardrops no)
	)
	(paper "A4")
	(title_block
		(title "04192023_DAF0TMB3IC0_F0TG_MB_C_brd_V02_OCP.brd")
		(comment 1 "Grand Teton / footprints 4091-4092 of 8354")
	)
	(layers
		(0 "F.Cu" signal "TOP")
		(4 "In1.Cu" signal "GND")
		(6 "In2.Cu" signal "IN1")
		(8 "In3.Cu" signal "GND1")
		(10 "In4.Cu" signal "IN2")
		(12 "In5.Cu" signal "GND2")
		(14 "In6.Cu" signal "IN3")
		(16 "In7.Cu" signal "GND3")
		(18 "In8.Cu" signal "VCC")
		(20 "In9.Cu" signal "VCC1")
		(22 "In10.Cu" signal "GND4")
		(24 "In11.Cu" signal "IN4")
		(26 "In12.Cu" signal "GND5")
		(28 "In13.Cu" signal "IN5")
		(30 "In14.Cu" signal "GND6")
		(32 "In15.Cu" signal "IN6")
		(34 "In16.Cu" signal "GND7")
		(2 "B.Cu" signal "BOTTOM")
		(9 "F.Adhes" user "F.Adhesive")
		(11 "B.Adhes" user "B.Adhesive")
		(13 "F.Paste" user "Package Geometry/Pastemask Top")
		(15 "B.Paste" user "Package Geometry/Pastemask Bottom")
		(5 "F.SilkS" user "Ref Des/Silkscreen Top")
		(7 "B.SilkS" user "Ref Des/Silkscreen Bottom")
		(1 "F.Mask" user "Board Geometry/Soldermask Top")
		(3 "B.Mask" user "Board Geometry/Soldermask Bottom")
		(17 "Dwgs.User" user "User.Drawings")
		(19 "Cmts.User" user "User.Comments")
		(21 "Eco1.User" user "User.Eco1")
		(23 "Eco2.User" user "User.Eco2")
		(25 "Edge.Cuts" user "Board Geometry/Outline")
		(27 "Margin" user)
		(31 "F.CrtYd" user "Package Geometry/Place Bound Top")
		(29 "B.CrtYd" user "Package Geometry/Place Bound Bottom")
		(35 "F.Fab" user "Ref Des/Assembly Top")
		(33 "B.Fab" user "Ref Des/Assembly Bottom")
	)
	(footprint ""
		(layer "F.Cu")
		(at 173.609 -100.294948 -90)
		(property "Reference" "R6008"
			(at 0 0 270)
			(layer "F.SilkS")
			(hide yes)
			(effects
				(font
					(size 1.27 1.27)
				)
			)
		)
		(property "Value" ""
			(at 0 0 270)
			(layer "F.Fab")
			(effects
				(font
					(size 1.27 1.27)
				)
			)
		)
		(duplicate_pad_numbers_are_jumpers no)
		(fp_line
			(start -0.7874 0.4064)
			(end -0.7874 -0.4064)
			(stroke
				(width 0.1524)
				(type default)
			)
			(layer "F.SilkS")
		)
		(fp_line
			(start 0.7874 0.4064)
			(end -0.7874 0.4064)
			(stroke
				(width 0.1524)
				(type default)
			)
			(layer "F.SilkS")
		)
		(fp_line
			(start -0.7874 -0.4064)
			(end 0.7874 -0.4064)
			(stroke
				(width 0.1524)
				(type default)
			)
			(layer "F.SilkS")
		)
		(fp_line
			(start 0.7874 -0.4064)
			(end 0.7874 0.4064)
			(stroke
				(width 0.1524)
				(type default)
			)
			(layer "F.SilkS")
		)
		(fp_line
			(start -0.67945 0.3048)
			(end -0.67945 -0.305054)
			(stroke
				(width 0.1)
				(type default)
			)
			(layer "F.Fab")
		)
		(fp_line
			(start -0.12065 0.3048)
			(end -0.67945 0.3048)
			(stroke
				(width 0.1)
				(type default)
			)
			(layer "F.Fab")
		)
		(fp_line
			(start 0.120396 0.3048)
			(end 0.120396 0.2794)
			(stroke
				(width 0.1)
				(type default)
			)
			(layer "F.Fab")
		)
		(fp_line
			(start 0.67945 0.3048)
			(end 0.120396 0.3048)
			(stroke
				(width 0.1)
				(type default)
			)
			(layer "F.Fab")
		)
		(fp_line
			(start -0.12065 0.2794)
			(end -0.12065 0.3048)
			(stroke
				(width 0.1)
				(type default)
			)
			(layer "F.Fab")
		)
		(fp_line
			(start 0.120396 0.2794)
			(end -0.12065 0.2794)
			(stroke
				(width 0.1)
				(type default)
			)
			(layer "F.Fab")
		)
		(fp_line
			(start -0.12065 -0.2794)
			(end 0.12065 -0.2794)
			(stroke
				(width 0.1)
				(type default)
			)
			(layer "F.Fab")
		)
		(fp_line
			(start 0.12065 -0.2794)
			(end 0.12065 -0.3048)
			(stroke
				(width 0.1)
				(type default)
			)
			(layer "F.Fab")
		)
		(fp_line
			(start 0.12065 -0.3048)
			(end 0.67945 -0.3048)
			(stroke
				(width 0.1)
				(type default)
			)
			(layer "F.Fab")
		)
		(fp_line
			(start 0.67945 -0.3048)
			(end 0.67945 0.3048)
			(stroke
				(width 0.1)
				(type default)
			)
			(layer "F.Fab")
		)
		(fp_line
			(start -0.67945 -0.305054)
			(end -0.12065 -0.305054)
			(stroke
				(width 0.1)
				(type default)
			)
			(layer "F.Fab")
		)
		(fp_line
			(start -0.12065 -0.305054)
			(end -0.12065 -0.2794)
			(stroke
				(width 0.1)
				(type default)
			)
			(layer "F.Fab")
		)
		(pad "1" smd circle
			(at -0.40005 0 270)
			(size 0 0)
			(layers "F.Cu" "F.Mask" "F.Paste")
			(net "SGPIO_SCM_DO_<0>")
		)
		(pad "2" smd circle
			(at 0.40005 0 270)
			(size 0 0)
			(layers "F.Cu" "F.Mask" "F.Paste")
			(net "SGPIO_SCM_DO_R_<0>")
		)
	)
	(footprint ""
		(layer "F.Cu")
		(at 422.339516 -356.32644 180)
		(property "Reference" "PR133"
			(at 0 0 180)
			(layer "F.SilkS")
			(hide yes)
			(effects
				(font
					(size 1.27 1.27)
				)
			)
		)
		(property "Value" ""
			(at 0 0 180)
			(layer "F.Fab")
			(effects
				(font
					(size 1.27 1.27)
				)
			)
		)
		(duplicate_pad_numbers_are_jumpers no)
		(fp_line
			(start 0.7874 0.4064)
			(end -0.7874 0.4064)
			(stroke
				(width 0.1524)
				(type default)
			)
			(layer "F.SilkS")
		)
		(fp_line
			(start 0.7874 -0.4064)
			(end 0.7874 0.4064)
			(stroke
				(width 0.1524)
				(type default)
			)
			(layer "F.SilkS")
		)
		(fp_line
			(start -0.7874 0.4064)
			(end -0.7874 -0.4064)
			(stroke
				(width 0.1524)
				(type default)
			)
			(layer "F.SilkS")
		)
		(fp_line
			(start -0.7874 -0.4064)
			(end 0.7874 -0.4064)
			(stroke
				(width 0.1524)
				(type default)
			)
			(layer "F.SilkS")
		)
		(fp_line
			(start 0.67945 0.3048)
			(end 0.120396 0.3048)
			(stroke
				(width 0.1)
				(type default)
			)
			(layer "F.Fab")
		)
		(fp_line
			(start 0.67945 -0.3048)
			(end 0.67945 0.3048)
			(stroke
				(width 0.1)
				(type default)
			)
			(layer "F.Fab")
		)
		(fp_line
			(start 0.12065 -0.2794)
			(end 0.12065 -0.3048)
			(stroke
				(width 0.1)
				(type default)
			)
			(layer "F.Fab")
		)
		(fp_line
			(start 0.12065 -0.3048)
			(end 0.67945 -0.3048)
			(stroke
				(width 0.1)
				(type default)
			)
			(layer "F.Fab")
		)
		(fp_line
			(start 0.120396 0.3048)
			(end 0.120396 0.2794)
			(stroke
				(width 0.1)
				(type default)
			)
			(layer "F.Fab")
		)
		(fp_line
			(start 0.120396 0.2794)
			(end -0.12065 0.2794)
			(stroke
				(width 0.1)
				(type default)
			)
			(layer "F.Fab")
		)
		(fp_line
			(start -0.12065 0.3048)
			(end -0.67945 0.3048)
			(stroke
				(width 0.1)
				(type default)
			)
			(layer "F.Fab")
		)
		(fp_line
			(start -0.12065 0.2794)
			(end -0.12065 0.3048)
			(stroke
				(width 0.1)
				(type default)
			)
			(layer "F.Fab")
		)
		(fp_line
			(start -0.12065 -0.2794)
			(end 0.12065 -0.2794)
			(stroke
				(width 0.1)
				(type default)
			)
			(layer "F.Fab")
		)
		(fp_line
			(start -0.12065 -0.305054)
			(end -0.12065 -0.2794)
			(stroke
				(width 0.1)
				(type default)
			)
			(layer "F.Fab")
		)
		(fp_line
			(start -0.67945 0.3048)
			(end -0.67945 -0.305054)
			(stroke
				(width 0.1)
				(type default)
			)
			(layer "F.Fab")
		)
		(fp_line
			(start -0.67945 -0.305054)
			(end -0.12065 -0.305054)
			(stroke
				(width 0.1)
				(type default)
			)
			(layer "F.Fab")
		)
		(pad "1" smd circle
			(at -0.40005 0 180)
			(size 0 0)
			(layers "F.Cu" "F.Mask" "F.Paste")
			(net "GND")
		)
		(pad "2" smd circle
			(at 0.40005 0 180)
			(size 0 0)
			(layers "F.Cu" "F.Mask" "F.Paste")
			(net "PVDD11_S3_P0_LSET1")
		)
	)
)
